(kicad_pcb
	(version 20260206)
	(generator "pcbnew")
	(generator_version "10.0")
	(general
		(thickness 1.6)
		(legacy_teardrops no)
	)
	(paper "A4")
	(title_block
		(title "12092022_DA0F0TFB6D0_F0T_FAN_BOARD_MP5048_D_brd_v02_OCP.brd")
		(comment 1 "Grand Teton / footprints 554-559 of 924")
	)
	(layers
		(0 "F.Cu" signal "TOP")
		(4 "In1.Cu" signal "GND")
		(6 "In2.Cu" signal "IN1")
		(8 "In3.Cu" signal "IN2")
		(10 "In4.Cu" signal "GND1")
		(2 "B.Cu" signal "BOTTOM")
		(9 "F.Adhes" user "F.Adhesive")
		(11 "B.Adhes" user "B.Adhesive")
		(13 "F.Paste" user "Package Geometry/Pastemask Top")
		(15 "B.Paste" user "Package Geometry/Pastemask Bottom")
		(5 "F.SilkS" user "Ref Des/Silkscreen Top")
		(7 "B.SilkS" user "Ref Des/Silkscreen Bottom")
		(1 "F.Mask" user "Board Geometry/Soldermask Top")
		(3 "B.Mask" user "Board Geometry/Soldermask Bottom")
		(17 "Dwgs.User" user "User.Drawings")
		(19 "Cmts.User" user "User.Comments")
		(21 "Eco1.User" user "User.Eco1")
		(23 "Eco2.User" user "User.Eco2")
		(25 "Edge.Cuts" user "Board Geometry/Outline")
		(27 "Margin" user)
		(31 "F.CrtYd" user "Package Geometry/Place Bound Top")
		(29 "B.CrtYd" user "Package Geometry/Place Bound Bottom")
		(35 "F.Fab" user "Ref Des/Assembly Top")
		(33 "B.Fab" user "Ref Des/Assembly Bottom")
	)
	(footprint ""
		(layer "F.Cu")
		(at 42.037 -187.96)
		(property "Reference" "R4964"
			(at 0 0 0)
			(layer "F.SilkS")
			(hide yes)
			(effects
				(font
					(size 1.27 1.27)
				)
			)
		)
		(property "Value" ""
			(at 0 0 0)
			(layer "F.Fab")
			(effects
				(font
					(size 1.27 1.27)
				)
			)
		)
		(duplicate_pad_numbers_are_jumpers no)
		(fp_line
			(start -0.7874 -0.4064)
			(end 0.7874 -0.4064)
			(stroke
				(width 0.1524)
				(type default)
			)
			(layer "F.SilkS")
		)
		(fp_line
			(start -0.7874 0.4064)
			(end -0.7874 -0.4064)
			(stroke
				(width 0.1524)
				(type default)
			)
			(layer "F.SilkS")
		)
		(fp_line
			(start 0.7874 -0.4064)
			(end 0.7874 0.4064)
			(stroke
				(width 0.1524)
				(type default)
			)
			(layer "F.SilkS")
		)
		(fp_line
			(start 0.7874 0.4064)
			(end -0.7874 0.4064)
			(stroke
				(width 0.1524)
				(type default)
			)
			(layer "F.SilkS")
		)
		(fp_line
			(start -0.67945 -0.305054)
			(end -0.12065 -0.305054)
			(stroke
				(width 0.1)
				(type default)
			)
			(layer "F.Fab")
		)
		(fp_line
			(start -0.67945 0.3048)
			(end -0.67945 -0.305054)
			(stroke
				(width 0.1)
				(type default)
			)
			(layer "F.Fab")
		)
		(fp_line
			(start -0.12065 -0.305054)
			(end -0.12065 -0.2794)
			(stroke
				(width 0.1)
				(type default)
			)
			(layer "F.Fab")
		)
		(fp_line
			(start -0.12065 -0.2794)
			(end 0.12065 -0.2794)
			(stroke
				(width 0.1)
				(type default)
			)
			(layer "F.Fab")
		)
		(fp_line
			(start -0.12065 0.2794)
			(end -0.12065 0.3048)
			(stroke
				(width 0.1)
				(type default)
			)
			(layer "F.Fab")
		)
		(fp_line
			(start -0.12065 0.3048)
			(end -0.67945 0.3048)
			(stroke
				(width 0.1)
				(type default)
			)
			(layer "F.Fab")
		)
		(fp_line
			(start 0.120396 0.2794)
			(end -0.12065 0.2794)
			(stroke
				(width 0.1)
				(type default)
			)
			(layer "F.Fab")
		)
		(fp_line
			(start 0.120396 0.3048)
			(end 0.120396 0.2794)
			(stroke
				(width 0.1)
				(type default)
			)
			(layer "F.Fab")
		)
		(fp_line
			(start 0.12065 -0.3048)
			(end 0.67945 -0.3048)
			(stroke
				(width 0.1)
				(type default)
			)
			(layer "F.Fab")
		)
		(fp_line
			(start 0.12065 -0.2794)
			(end 0.12065 -0.3048)
			(stroke
				(width 0.1)
				(type default)
			)
			(layer "F.Fab")
		)
		(fp_line
			(start 0.67945 -0.3048)
			(end 0.67945 0.3048)
			(stroke
				(width 0.1)
				(type default)
			)
			(layer "F.Fab")
		)
		(fp_line
			(start 0.67945 0.3048)
			(end 0.120396 0.3048)
			(stroke
				(width 0.1)
				(type default)
			)
			(layer "F.Fab")
		)
		(pad "1" smd circle
			(at -0.40005 0)
			(size 0 0)
			(layers "F.Cu" "F.Mask" "F.Paste")
			(net "PD_FAN_BUFF_INPUT_U337E")
		)
		(pad "2" smd circle
			(at 0.40005 0)
			(size 0 0)
			(layers "F.Cu" "F.Mask" "F.Paste")
			(net "P3V3_AUX")
		)
	)
	(footprint ""
		(layer "F.Cu")
		(at 25.273 -20.713954)
		(property "Reference" "R4970"
			(at 0 0 0)
			(layer "F.SilkS")
			(hide yes)
			(effects
				(font
					(size 1.27 1.27)
				)
			)
		)
		(property "Value" ""
			(at 0 0 0)
			(layer "F.Fab")
			(effects
				(font
					(size 1.27 1.27)
				)
			)
		)
		(duplicate_pad_numbers_are_jumpers no)
		(fp_line
			(start -0.7874 -0.4064)
			(end 0.7874 -0.4064)
			(stroke
				(width 0.1524)
				(type default)
			)
			(layer "F.SilkS")
		)
		(fp_line
			(start -0.7874 0.4064)
			(end -0.7874 -0.4064)
			(stroke
				(width 0.1524)
				(type default)
			)
			(layer "F.SilkS")
		)
		(fp_line
			(start 0.7874 -0.4064)
			(end 0.7874 0.4064)
			(stroke
				(width 0.1524)
				(type default)
			)
			(layer "F.SilkS")
		)
		(fp_line
			(start 0.7874 0.4064)
			(end -0.7874 0.4064)
			(stroke
				(width 0.1524)
				(type default)
			)
			(layer "F.SilkS")
		)
		(fp_line
			(start -0.67945 -0.305054)
			(end -0.12065 -0.305054)
			(stroke
				(width 0.1)
				(type default)
			)
			(layer "F.Fab")
		)
		(fp_line
			(start -0.67945 0.3048)
			(end -0.67945 -0.305054)
			(stroke
				(width 0.1)
				(type default)
			)
			(layer "F.Fab")
		)
		(fp_line
			(start -0.12065 -0.305054)
			(end -0.12065 -0.2794)
			(stroke
				(width 0.1)
				(type default)
			)
			(layer "F.Fab")
		)
		(fp_line
			(start -0.12065 -0.2794)
			(end 0.12065 -0.2794)
			(stroke
				(width 0.1)
				(type default)
			)
			(layer "F.Fab")
		)
		(fp_line
			(start -0.12065 0.2794)
			(end -0.12065 0.3048)
			(stroke
				(width 0.1)
				(type default)
			)
			(layer "F.Fab")
		)
		(fp_line
			(start -0.12065 0.3048)
			(end -0.67945 0.3048)
			(stroke
				(width 0.1)
				(type default)
			)
			(layer "F.Fab")
		)
		(fp_line
			(start 0.120396 0.2794)
			(end -0.12065 0.2794)
			(stroke
				(width 0.1)
				(type default)
			)
			(layer "F.Fab")
		)
		(fp_line
			(start 0.120396 0.3048)
			(end 0.120396 0.2794)
			(stroke
				(width 0.1)
				(type default)
			)
			(layer "F.Fab")
		)
		(fp_line
			(start 0.12065 -0.3048)
			(end 0.67945 -0.3048)
			(stroke
				(width 0.1)
				(type default)
			)
			(layer "F.Fab")
		)
		(fp_line
			(start 0.12065 -0.2794)
			(end 0.12065 -0.3048)
			(stroke
				(width 0.1)
				(type default)
			)
			(layer "F.Fab")
		)
		(fp_line
			(start 0.67945 -0.3048)
			(end 0.67945 0.3048)
			(stroke
				(width 0.1)
				(type default)
			)
			(layer "F.Fab")
		)
		(fp_line
			(start 0.67945 0.3048)
			(end 0.120396 0.3048)
			(stroke
				(width 0.1)
				(type default)
			)
			(layer "F.Fab")
		)
		(pad "1" smd circle
			(at -0.40005 0)
			(size 0 0)
			(layers "F.Cu" "F.Mask" "F.Paste")
			(net "P52V_FAN_EN_R")
		)
		(pad "2" smd circle
			(at 0.40005 0)
			(size 0 0)
			(layers "F.Cu" "F.Mask" "F.Paste")
			(net "P52V_FAN_EN")
		)
	)
	(footprint ""
		(layer "F.Cu")
		(at 14.859 -128.524)
		(property "Reference" "R5614"
			(at 0 0 0)
			(layer "F.SilkS")
			(hide yes)
			(effects
				(font
					(size 1.27 1.27)
				)
			)
		)
		(property "Value" ""
			(at 0 0 0)
			(layer "F.Fab")
			(effects
				(font
					(size 1.27 1.27)
				)
			)
		)
		(duplicate_pad_numbers_are_jumpers no)
		(fp_line
			(start -0.7874 -0.4064)
			(end 0.7874 -0.4064)
			(stroke
				(width 0.1524)
				(type default)
			)
			(layer "F.SilkS")
		)
		(fp_line
			(start -0.7874 0.4064)
			(end -0.7874 -0.4064)
			(stroke
				(width 0.1524)
				(type default)
			)
			(layer "F.SilkS")
		)
		(fp_line
			(start 0.7874 -0.4064)
			(end 0.7874 0.4064)
			(stroke
				(width 0.1524)
				(type default)
			)
			(layer "F.SilkS")
		)
		(fp_line
			(start 0.7874 0.4064)
			(end -0.7874 0.4064)
			(stroke
				(width 0.1524)
				(type default)
			)
			(layer "F.SilkS")
		)
		(fp_line
			(start -0.67945 -0.305054)
			(end -0.12065 -0.305054)
			(stroke
				(width 0.1)
				(type default)
			)
			(layer "F.Fab")
		)
		(fp_line
			(start -0.67945 0.3048)
			(end -0.67945 -0.305054)
			(stroke
				(width 0.1)
				(type default)
			)
			(layer "F.Fab")
		)
		(fp_line
			(start -0.12065 -0.305054)
			(end -0.12065 -0.2794)
			(stroke
				(width 0.1)
				(type default)
			)
			(layer "F.Fab")
		)
		(fp_line
			(start -0.12065 -0.2794)
			(end 0.12065 -0.2794)
			(stroke
				(width 0.1)
				(type default)
			)
			(layer "F.Fab")
		)
		(fp_line
			(start -0.12065 0.2794)
			(end -0.12065 0.3048)
			(stroke
				(width 0.1)
				(type default)
			)
			(layer "F.Fab")
		)
		(fp_line
			(start -0.12065 0.3048)
			(end -0.67945 0.3048)
			(stroke
				(width 0.1)
				(type default)
			)
			(layer "F.Fab")
		)
		(fp_line
			(start 0.120396 0.2794)
			(end -0.12065 0.2794)
			(stroke
				(width 0.1)
				(type default)
			)
			(layer "F.Fab")
		)
		(fp_line
			(start 0.120396 0.3048)
			(end 0.120396 0.2794)
			(stroke
				(width 0.1)
				(type default)
			)
			(layer "F.Fab")
		)
		(fp_line
			(start 0.12065 -0.3048)
			(end 0.67945 -0.3048)
			(stroke
				(width 0.1)
				(type default)
			)
			(layer "F.Fab")
		)
		(fp_line
			(start 0.12065 -0.2794)
			(end 0.12065 -0.3048)
			(stroke
				(width 0.1)
				(type default)
			)
			(layer "F.Fab")
		)
		(fp_line
			(start 0.67945 -0.3048)
			(end 0.67945 0.3048)
			(stroke
				(width 0.1)
				(type default)
			)
			(layer "F.Fab")
		)
		(fp_line
			(start 0.67945 0.3048)
			(end 0.120396 0.3048)
			(stroke
				(width 0.1)
				(type default)
			)
			(layer "F.Fab")
		)
		(pad "1" smd rect
			(at -0.40005 0 180)
			(size 0.4572 0.508)
			(layers "F.Cu" "F.Mask" "F.Paste")
			(net "FAN_5_TACH_OL")
		)
		(pad "2" smd rect
			(at 0.40005 0 180)
			(size 0.4572 0.508)
			(layers "F.Cu" "F.Mask" "F.Paste")
			(net "FAN_5_TACH_OL_R1")
		)
	)
	(footprint ""
		(layer "F.Cu")
		(at 14.351 -296.799 180)
		(property "Reference" "R5382"
			(at 0 0 180)
			(layer "F.SilkS")
			(hide yes)
			(effects
				(font
					(size 1.27 1.27)
				)
			)
		)
		(property "Value" ""
			(at 0 0 180)
			(layer "F.Fab")
			(effects
				(font
					(size 1.27 1.27)
				)
			)
		)
		(duplicate_pad_numbers_are_jumpers no)
		(fp_line
			(start 0.7874 0.4064)
			(end -0.7874 0.4064)
			(stroke
				(width 0.1524)
				(type default)
			)
			(layer "F.SilkS")
		)
		(fp_line
			(start 0.7874 -0.4064)
			(end 0.7874 0.4064)
			(stroke
				(width 0.1524)
				(type default)
			)
			(layer "F.SilkS")
		)
		(fp_line
			(start -0.7874 0.4064)
			(end -0.7874 -0.4064)
			(stroke
				(width 0.1524)
				(type default)
			)
			(layer "F.SilkS")
		)
		(fp_line
			(start -0.7874 -0.4064)
			(end 0.7874 -0.4064)
			(stroke
				(width 0.1524)
				(type default)
			)
			(layer "F.SilkS")
		)
		(fp_line
			(start 0.67945 0.3048)
			(end 0.120396 0.3048)
			(stroke
				(width 0.1)
				(type default)
			)
			(layer "F.Fab")
		)
		(fp_line
			(start 0.67945 -0.3048)
			(end 0.67945 0.3048)
			(stroke
				(width 0.1)
				(type default)
			)
			(layer "F.Fab")
		)
		(fp_line
			(start 0.12065 -0.2794)
			(end 0.12065 -0.3048)
			(stroke
				(width 0.1)
				(type default)
			)
			(layer "F.Fab")
		)
		(fp_line
			(start 0.12065 -0.3048)
			(end 0.67945 -0.3048)
			(stroke
				(width 0.1)
				(type default)
			)
			(layer "F.Fab")
		)
		(fp_line
			(start 0.120396 0.3048)
			(end 0.120396 0.2794)
			(stroke
				(width 0.1)
				(type default)
			)
			(layer "F.Fab")
		)
		(fp_line
			(start 0.120396 0.2794)
			(end -0.12065 0.2794)
			(stroke
				(width 0.1)
				(type default)
			)
			(layer "F.Fab")
		)
		(fp_line
			(start -0.12065 0.3048)
			(end -0.67945 0.3048)
			(stroke
				(width 0.1)
				(type default)
			)
			(layer "F.Fab")
		)
		(fp_line
			(start -0.12065 0.2794)
			(end -0.12065 0.3048)
			(stroke
				(width 0.1)
				(type default)
			)
			(layer "F.Fab")
		)
		(fp_line
			(start -0.12065 -0.2794)
			(end 0.12065 -0.2794)
			(stroke
				(width 0.1)
				(type default)
			)
			(layer "F.Fab")
		)
		(fp_line
			(start -0.12065 -0.305054)
			(end -0.12065 -0.2794)
			(stroke
				(width 0.1)
				(type default)
			)
			(layer "F.Fab")
		)
		(fp_line
			(start -0.67945 0.3048)
			(end -0.67945 -0.305054)
			(stroke
				(width 0.1)
				(type default)
			)
			(layer "F.Fab")
		)
		(fp_line
			(start -0.67945 -0.305054)
			(end -0.12065 -0.305054)
			(stroke
				(width 0.1)
				(type default)
			)
			(layer "F.Fab")
		)
		(pad "1" smd rect
			(at -0.40005 0)
			(size 0.4572 0.508)
			(layers "F.Cu" "F.Mask" "F.Paste")
			(net "FAN_7_FAIL_LED_R_N")
		)
		(pad "2" smd rect
			(at 0.40005 0)
			(size 0.4572 0.508)
			(layers "F.Cu" "F.Mask" "F.Paste")
			(net "FAN_7_FAIL_R_LED_N")
		)
	)
	(footprint ""
		(layer "F.Cu")
		(at 23.241 -119.126 -90)
		(property "Reference" "R5513"
			(at 0 0 270)
			(layer "F.SilkS")
			(hide yes)
			(effects
				(font
					(size 1.27 1.27)
				)
			)
		)
		(property "Value" ""
			(at 0 0 270)
			(layer "F.Fab")
			(effects
				(font
					(size 1.27 1.27)
				)
			)
		)
		(duplicate_pad_numbers_are_jumpers no)
		(fp_line
			(start -0.7874 0.4064)
			(end -0.7874 -0.4064)
			(stroke
				(width 0.1524)
				(type default)
			)
			(layer "F.SilkS")
		)
		(fp_line
			(start 0.7874 0.4064)
			(end -0.7874 0.4064)
			(stroke
				(width 0.1524)
				(type default)
			)
			(layer "F.SilkS")
		)
		(fp_line
			(start -0.7874 -0.4064)
			(end 0.7874 -0.4064)
			(stroke
				(width 0.1524)
				(type default)
			)
			(layer "F.SilkS")
		)
		(fp_line
			(start 0.7874 -0.4064)
			(end 0.7874 0.4064)
			(stroke
				(width 0.1524)
				(type default)
			)
			(layer "F.SilkS")
		)
		(fp_line
			(start -0.67945 0.3048)
			(end -0.67945 -0.305054)
			(stroke
				(width 0.1)
				(type default)
			)
			(layer "F.Fab")
		)
		(fp_line
			(start -0.12065 0.3048)
			(end -0.67945 0.3048)
			(stroke
				(width 0.1)
				(type default)
			)
			(layer "F.Fab")
		)
		(fp_line
			(start 0.120396 0.3048)
			(end 0.120396 0.2794)
			(stroke
				(width 0.1)
				(type default)
			)
			(layer "F.Fab")
		)
		(fp_line
			(start 0.67945 0.3048)
			(end 0.120396 0.3048)
			(stroke
				(width 0.1)
				(type default)
			)
			(layer "F.Fab")
		)
		(fp_line
			(start -0.12065 0.2794)
			(end -0.12065 0.3048)
			(stroke
				(width 0.1)
				(type default)
			)
			(layer "F.Fab")
		)
		(fp_line
			(start 0.120396 0.2794)
			(end -0.12065 0.2794)
			(stroke
				(width 0.1)
				(type default)
			)
			(layer "F.Fab")
		)
		(fp_line
			(start -0.12065 -0.2794)
			(end 0.12065 -0.2794)
			(stroke
				(width 0.1)
				(type default)
			)
			(layer "F.Fab")
		)
		(fp_line
			(start 0.12065 -0.2794)
			(end 0.12065 -0.3048)
			(stroke
				(width 0.1)
				(type default)
			)
			(layer "F.Fab")
		)
		(fp_line
			(start 0.12065 -0.3048)
			(end 0.67945 -0.3048)
			(stroke
				(width 0.1)
				(type default)
			)
			(layer "F.Fab")
		)
		(fp_line
			(start 0.67945 -0.3048)
			(end 0.67945 0.3048)
			(stroke
				(width 0.1)
				(type default)
			)
			(layer "F.Fab")
		)
		(fp_line
			(start -0.67945 -0.305054)
			(end -0.12065 -0.305054)
			(stroke
				(width 0.1)
				(type default)
			)
			(layer "F.Fab")
		)
		(fp_line
			(start -0.12065 -0.305054)
			(end -0.12065 -0.2794)
			(stroke
				(width 0.1)
				(type default)
			)
			(layer "F.Fab")
		)
		(pad "1" smd circle
			(at -0.40005 0 270)
			(size 0 0)
			(layers "F.Cu" "F.Mask" "F.Paste")
			(net "P3V3_AUX")
		)
		(pad "2" smd circle
			(at 0.40005 0 270)
			(size 0 0)
			(layers "F.Cu" "F.Mask" "F.Paste")
			(net "FAN_2_PWM_BUF")
		)
	)
	(footprint ""
		(layer "F.Cu")
		(at 15.621 -164.338)
		(property "Reference" "C54"
			(at 0 0 0)
			(layer "F.SilkS")
			(hide yes)
			(effects
				(font
					(size 1.27 1.27)
				)
			)
		)
		(property "Value" ""
			(at 0 0 0)
			(layer "F.Fab")
			(effects
				(font
					(size 1.27 1.27)
				)
			)
		)
		(duplicate_pad_numbers_are_jumpers no)
		(fp_line
			(start -0.7874 -0.4064)
			(end 0.7874 -0.4064)
			(stroke
				(width 0.1524)
				(type default)
			)
			(layer "F.SilkS")
		)
		(fp_line
			(start -0.7874 0.4064)
			(end -0.7874 -0.4064)
			(stroke
				(width 0.1524)
				(type default)
			)
			(layer "F.SilkS")
		)
		(fp_line
			(start 0.7874 -0.4064)
			(end 0.7874 0.4064)
			(stroke
				(width 0.1524)
				(type default)
			)
			(layer "F.SilkS")
		)
		(fp_line
			(start 0.7874 0.4064)
			(end -0.7874 0.4064)
			(stroke
				(width 0.1524)
				(type default)
			)
			(layer "F.SilkS")
		)
		(fp_line
			(start -0.67945 -0.305054)
			(end -0.12065 -0.305054)
			(stroke
				(width 0.1)
				(type default)
			)
			(layer "F.Fab")
		)
		(fp_line
			(start -0.67945 0.3048)
			(end -0.67945 -0.305054)
			(stroke
				(width 0.1)
				(type default)
			)
			(layer "F.Fab")
		)
		(fp_line
			(start -0.12065 -0.305054)
			(end -0.12065 -0.2794)
			(stroke
				(width 0.1)
				(type default)
			)
			(layer "F.Fab")
		)
		(fp_line
			(start -0.12065 -0.2794)
			(end 0.12065 -0.2794)
			(stroke
				(width 0.1)
				(type default)
			)
			(layer "F.Fab")
		)
		(fp_line
			(start -0.12065 0.2794)
			(end -0.12065 0.3048)
			(stroke
				(width 0.1)
				(type default)
			)
			(layer "F.Fab")
		)
		(fp_line
			(start -0.12065 0.3048)
			(end -0.67945 0.3048)
			(stroke
				(width 0.1)
				(type default)
			)
			(layer "F.Fab")
		)
		(fp_line
			(start 0.120396 0.2794)
			(end -0.12065 0.2794)
			(stroke
				(width 0.1)
				(type default)
			)
			(layer "F.Fab")
		)
		(fp_line
			(start 0.120396 0.3048)
			(end 0.120396 0.2794)
			(stroke
				(width 0.1)
				(type default)
			)
			(layer "F.Fab")
		)
		(fp_line
			(start 0.12065 -0.3048)
			(end 0.67945 -0.3048)
			(stroke
				(width 0.1)
				(type default)
			)
			(layer "F.Fab")
		)
		(fp_line
			(start 0.12065 -0.2794)
			(end 0.12065 -0.3048)
			(stroke
				(width 0.1)
				(type default)
			)
			(layer "F.Fab")
		)
		(fp_line
			(start 0.67945 -0.3048)
			(end 0.67945 0.3048)
			(stroke
				(width 0.1)
				(type default)
			)
			(layer "F.Fab")
		)
		(fp_line
			(start 0.67945 0.3048)
			(end 0.120396 0.3048)
			(stroke
				(width 0.1)
				(type default)
			)
			(layer "F.Fab")
		)
		(pad "1" smd circle
			(at -0.40005 0)
			(size 0 0)
			(layers "F.Cu" "F.Mask" "F.Paste")
			(net "FAN_1_PRESENT_N")
		)
		(pad "2" smd circle
			(at 0.40005 0)
			(size 0 0)
			(layers "F.Cu" "F.Mask" "F.Paste")
			(net "GND")
		)
	)
)
